(kicad_pcb
	(version 20260206)
	(generator "pcbnew")
	(generator_version "10.0")
	(general
		(thickness 1.6)
		(legacy_teardrops no)
	)
	(paper "A4")
	(title_block
		(title "Bryce Canyon_R.DPB_16317-1_OCP.brd")
		(comment 1 "Bryce Canyon / footprints 868-872 of 2099")
	)
	(layers
		(0 "F.Cu" signal "TOP")
		(4 "In1.Cu" signal "L2GND")
		(6 "In2.Cu" signal "L3")
		(8 "In3.Cu" signal "L4VCC")
		(10 "In4.Cu" signal "L5VCC")
		(12 "In5.Cu" signal "L6")
		(14 "In6.Cu" signal "L7GND")
		(2 "B.Cu" signal "BOTTOM")
		(9 "F.Adhes" user "F.Adhesive")
		(11 "B.Adhes" user "B.Adhesive")
		(13 "F.Paste" user "Package Geometry/Pastemask Top")
		(15 "B.Paste" user "Package Geometry/Pastemask Bottom")
		(5 "F.SilkS" user "Ref Des/Silkscreen Top")
		(7 "B.SilkS" user "Ref Des/Silkscreen Bottom")
		(1 "F.Mask" user "Board Geometry/Soldermask Top")
		(3 "B.Mask" user "Board Geometry/Soldermask Bottom")
		(17 "Dwgs.User" user "User.Drawings")
		(19 "Cmts.User" user "User.Comments")
		(21 "Eco1.User" user "User.Eco1")
		(23 "Eco2.User" user "User.Eco2")
		(25 "Edge.Cuts" user "Board Geometry/Outline")
		(27 "Margin" user)
		(31 "F.CrtYd" user "Package Geometry/Place Bound Top")
		(29 "B.CrtYd" user "Package Geometry/Place Bound Bottom")
		(35 "F.Fab" user "Ref Des/Assembly Top")
		(33 "B.Fab" user "Ref Des/Assembly Bottom")
	)
	(footprint ""
		(layer "F.Cu")
		(at 253.350522 -366.115346 180)
		(property "Reference" "U22"
			(at 0 0 180)
			(layer "F.SilkS")
			(hide yes)
			(effects
				(font
					(size 1.27 1.27)
				)
			)
		)
		(property "Value" "ADM1278-2ACPZ-RL-1-GP"
			(at -4.7625 -7.4422 180)
			(unlocked yes)
			(layer "F.Fab")
			(hide yes)
			(effects
				(font
					(size 1.016 1.016)
					(thickness 0.1524)
				)
			)
		)
		(property "Device Type" "QFN32-G3D45-UH32"
			(at -4.7625 -8.9662 180)
			(unlocked yes)
			(layer "F.Fab")
			(hide yes)
			(effects
				(font
					(size 1.016 1.016)
					(thickness 0.1524)
				)
			)
		)
		(duplicate_pad_numbers_are_jumpers no)
		(fp_line
			(start 4.0513 -0.749808)
			(end 3.2893 -0.749808)
			(stroke
				(width 0.1524)
				(type default)
			)
			(layer "F.SilkS")
		)
		(fp_line
			(start 3.7973 1.749552)
			(end 3.2893 1.749552)
			(stroke
				(width 0.1524)
				(type default)
			)
			(layer "F.SilkS")
		)
		(fp_line
			(start 3.5179 3.5179)
			(end 2.2479 3.5179)
			(stroke
				(width 0.1524)
				(type default)
			)
			(layer "F.SilkS")
		)
		(fp_line
			(start 3.5179 2.2479)
			(end 3.5179 3.5179)
			(stroke
				(width 0.1524)
				(type default)
			)
			(layer "F.SilkS")
		)
		(fp_line
			(start -0.250698 4.0513)
			(end -0.250698 3.2893)
			(stroke
				(width 0.1524)
				(type default)
			)
			(layer "F.SilkS")
		)
		(fp_line
			(start -0.250698 -3.7973)
			(end -0.250698 -3.2893)
			(stroke
				(width 0.1524)
				(type default)
			)
			(layer "F.SilkS")
		)
		(fp_line
			(start -3.5179 3.5179)
			(end -2.2479 3.5179)
			(stroke
				(width 0.1524)
				(type default)
			)
			(layer "F.SilkS")
		)
		(fp_line
			(start -3.5179 2.2479)
			(end -3.5179 3.5179)
			(stroke
				(width 0.1524)
				(type default)
			)
			(layer "F.SilkS")
		)
		(fp_line
			(start -3.5179 -2.2479)
			(end -3.5179 -3.5179)
			(stroke
				(width 0.1524)
				(type default)
			)
			(layer "F.SilkS")
		)
		(fp_line
			(start -3.5179 -3.5179)
			(end -2.2479 -3.5179)
			(stroke
				(width 0.1524)
				(type default)
			)
			(layer "F.SilkS")
		)
		(fp_line
			(start -3.7973 1.24968)
			(end -3.2893 1.24968)
			(stroke
				(width 0.1524)
				(type default)
			)
			(layer "F.SilkS")
		)
		(fp_line
			(start -4.0513 -1.24968)
			(end -3.2893 -1.24968)
			(stroke
				(width 0.1524)
				(type default)
			)
			(layer "F.SilkS")
		)
		(fp_poly
			(pts
				(xy 2.2479 -3.5179) (xy 3.5179 -2.2479) (xy 3.5179 -3.5179)
			)
			(stroke
				(width 0)
				(type default)
			)
			(fill yes)
			(layer "F.SilkS")
		)
		(fp_rect
			(start -2.5019 2.5019)
			(end 2.5019 -2.5019)
			(stroke
				(width 0)
				(type default)
			)
			(fill no)
			(layer "F.CrtYd")
		)
		(fp_poly
			(pts
				(xy -3.5179 3.5179) (xy -3.5179 -3.5179) (xy 3.5179 -3.5179) (xy 3.5179 3.5179) (xy -2.49682 3.5179)
				(xy -2.49682 2.5019) (xy 2.5019 2.5019) (xy 2.5019 -2.5019) (xy -2.5019 -2.5019) (xy -2.5019 3.5179)
			)
			(stroke
				(width 0)
				(type default)
			)
			(fill no)
			(layer "F.CrtYd")
		)
		(fp_rect
			(start -3.5179 3.5179)
			(end 3.5179 -3.5179)
			(stroke
				(width 0)
				(type default)
			)
			(fill no)
			(layer "F.Fab")
		)
		(pad "1" smd rect
			(at 1.75006 -2.5527 180)
			(size 0.3048 0.9144)
			(layers "F.Cu" "F.Mask" "F.Paste")
			(net "MB3_PSET_R")
		)
		(pad "2" smd rect
			(at 1.249934 -2.4765 180)
			(size 0.3048 1.0668)
			(layers "F.Cu" "F.Mask" "F.Paste")
			(net "MB3_VCAP_R")
		)
		(pad "3" smd rect
			(at 0.750062 -2.4765 180)
			(size 0.3048 1.0668)
			(layers "F.Cu" "F.Mask" "F.Paste")
			(net "MB3_ISET_R")
		)
		(pad "4" smd rect
			(at 0.249936 -2.4765 180)
			(size 0.3048 1.0668)
			(layers "F.Cu" "F.Mask" "F.Paste")
			(net "MB3_ISTART_R")
		)
		(pad "5" smd rect
			(at -0.249936 -2.4765 180)
			(size 0.3048 1.0668)
			(layers "F.Cu" "F.Mask" "F.Paste")
			(net "MB3_TIME_R")
		)
		(pad "6" smd rect
			(at -0.750062 -2.4765 180)
			(size 0.3048 1.0668)
			(layers "F.Cu" "F.Mask" "F.Paste")
			(net "Net_972")
		)
		(pad "7" smd rect
			(at -1.249934 -2.4765 180)
			(size 0.3048 1.0668)
			(layers "F.Cu" "F.Mask" "F.Paste")
			(net "MB3_CM_ADR1_R")
		)
		(pad "8" smd rect
			(at -1.75006 -2.5527 180)
			(size 0.3048 0.9144)
			(layers "F.Cu" "F.Mask" "F.Paste")
			(net "MB3_CM_ADR2_R")
		)
		(pad "9" smd rect
			(at -2.5527 -1.75006 180)
			(size 0.9144 0.3048)
			(layers "F.Cu" "F.Mask" "F.Paste")
			(net "MB3_SPISS_PD")
		)
		(pad "10" smd rect
			(at -2.4765 -1.249934 180)
			(size 1.0668 0.3048)
			(layers "F.Cu" "F.Mask" "F.Paste")
			(net "Net_976")
		)
		(pad "11" smd rect
			(at -2.4765 -0.750062 180)
			(size 1.0668 0.3048)
			(layers "F.Cu" "F.Mask" "F.Paste")
			(net "Net_975")
		)
		(pad "12" smd rect
			(at -2.4765 -0.249936 180)
			(size 1.0668 0.3048)
			(layers "F.Cu" "F.Mask" "F.Paste")
			(net "MB3_HS_ENABLE")
		)
		(pad "13" smd rect
			(at -2.4765 0.249936 180)
			(size 1.0668 0.3048)
			(layers "F.Cu" "F.Mask" "F.Paste")
			(net "Net_974")
		)
		(pad "14" smd rect
			(at -2.4765 0.750062 180)
			(size 1.0668 0.3048)
			(layers "F.Cu" "F.Mask" "F.Paste")
			(net "Net_973")
		)
		(pad "15" smd rect
			(at -2.4765 1.249934 180)
			(size 1.0668 0.3048)
			(layers "F.Cu" "F.Mask" "F.Paste")
			(net "MB3_SDA_R")
		)
		(pad "16" smd rect
			(at -2.5527 1.75006 180)
			(size 0.9144 0.3048)
			(layers "F.Cu" "F.Mask" "F.Paste")
			(net "MB3_SCL_R")
		)
		(pad "17" smd rect
			(at -1.75006 2.5527 180)
			(size 0.3048 0.9144)
			(layers "F.Cu" "F.Mask" "F.Paste")
			(net "MB3_RETRY_R")
		)
		(pad "18" smd rect
			(at -1.249934 2.4765 180)
			(size 0.3048 1.0668)
			(layers "F.Cu" "F.Mask" "F.Paste")
			(net "P12V_B_PGOOD")
		)
		(pad "19" smd rect
			(at -0.750062 2.4765 180)
			(size 0.3048 1.0668)
			(layers "F.Cu" "F.Mask" "F.Paste")
			(net "Net_977")
		)
		(pad "20" smd rect
			(at -0.249936 2.4765 180)
			(size 0.3048 1.0668)
			(layers "F.Cu" "F.Mask" "F.Paste")
			(net "MB3_CM_VOUT_R")
		)
		(pad "21" smd rect
			(at 0.249936 2.4765 180)
			(size 0.3048 1.0668)
			(layers "F.Cu" "F.Mask" "F.Paste")
			(net "MB3_P12V_PWGIN_R")
		)
		(pad "22" smd rect
			(at 0.750062 2.4765 180)
			(size 0.3048 1.0668)
			(layers "F.Cu" "F.Mask" "F.Paste")
			(net "AGND_CURRENT_DPB")
		)
		(pad "23" smd rect
			(at 1.249934 2.4765 180)
			(size 0.3048 1.0668)
			(layers "F.Cu" "F.Mask" "F.Paste")
			(net "GND")
		)
		(pad "24" smd rect
			(at 1.75006 2.5527 180)
			(size 0.3048 0.9144)
			(layers "F.Cu" "F.Mask" "F.Paste")
			(net "MB3_CM_GATE")
		)
		(pad "25" smd rect
			(at 2.5527 1.75006 180)
			(size 0.9144 0.3048)
			(layers "F.Cu" "F.Mask" "F.Paste")
			(net "MB3_TEMP")
		)
		(pad "26" smd rect
			(at 2.4765 1.249934 180)
			(size 1.0668 0.3048)
			(layers "F.Cu" "F.Mask" "F.Paste")
			(net "MB3_CM_SENSE_N")
		)
		(pad "27" smd rect
			(at 2.4765 0.750062 180)
			(size 1.0668 0.3048)
			(layers "F.Cu" "F.Mask" "F.Paste")
			(net "MB3_HS_SENSE_N")
		)
		(pad "28" smd rect
			(at 2.4765 0.249936 180)
			(size 1.0668 0.3048)
			(layers "F.Cu" "F.Mask" "F.Paste")
			(net "MB3_HS_SENSE_P")
		)
		(pad "29" smd rect
			(at 2.4765 -0.249936 180)
			(size 1.0668 0.3048)
			(layers "F.Cu" "F.Mask" "F.Paste")
			(net "MB3_CM_SENSE_P")
		)
		(pad "30" smd rect
			(at 2.4765 -0.750062 180)
			(size 1.0668 0.3048)
			(layers "F.Cu" "F.Mask" "F.Paste")
			(net "MB3_P12V_HS")
		)
		(pad "31" smd rect
			(at 2.4765 -1.249934 180)
			(size 1.0668 0.3048)
			(layers "F.Cu" "F.Mask" "F.Paste")
			(net "MB3_CM_UV_R")
		)
		(pad "32" smd rect
			(at 2.5527 -1.75006 180)
			(size 0.9144 0.3048)
			(layers "F.Cu" "F.Mask" "F.Paste")
			(net "MB3_CM_OV_R")
		)
		(pad "33" smd rect
			(at 0 0 180)
			(size 3.4544 3.4544)
			(layers "F.Cu" "F.Mask" "F.Paste")
			(net "AGND_CURRENT_DPB")
		)
	)
	(footprint ""
		(layer "F.Cu")
		(at 441.96 -99.187)
		(property "Reference" "R457"
			(at 0 0 0)
			(layer "F.SilkS")
			(hide yes)
			(effects
				(font
					(size 1.27 1.27)
				)
			)
		)
		(property "Value" "91R3F-1-GP"
			(at -0.0254 -2.5146 0)
			(unlocked yes)
			(layer "F.Fab")
			(hide yes)
			(effects
				(font
					(size 1.016 1.016)
					(thickness 0.1524)
				)
			)
		)
		(property "Device Type" "R603H22"
			(at -0.0254 -4.0386 0)
			(unlocked yes)
			(layer "F.Fab")
			(hide yes)
			(effects
				(font
					(size 1.016 1.016)
					(thickness 0.1524)
				)
			)
		)
		(duplicate_pad_numbers_are_jumpers no)
		(fp_line
			(start -0.4826 0)
			(end -0.2032 0)
			(stroke
				(width 0.2032)
				(type default)
			)
			(layer "F.SilkS")
		)
		(fp_line
			(start 0.2032 0)
			(end 0.4826 0)
			(stroke
				(width 0.2032)
				(type default)
			)
			(layer "F.SilkS")
		)
		(fp_rect
			(start -0.5842 1.3335)
			(end 0.5842 -1.3335)
			(stroke
				(width 0)
				(type default)
			)
			(fill no)
			(layer "F.CrtYd")
		)
		(fp_rect
			(start -0.5842 1.3335)
			(end 0.5842 -1.3335)
			(stroke
				(width 0)
				(type default)
			)
			(fill no)
			(layer "F.Fab")
		)
		(pad "1" smd custom
			(at 0 -0.762)
			(size 0.2159 0.2159)
			(layers "F.Cu" "F.Mask" "F.Paste")
			(net "P5V_B_4")
			(options
				(clearance outline)
				(anchor circle)
			)
			(primitives
				(gr_poly
					(pts
						(arc
							(start -0.3302 -0.4318)
							(mid -0.402042 -0.402042)
							(end -0.4318 -0.3302)
						)
						(arc
							(start -0.4318 0.3302)
							(mid -0.402042 0.402042)
							(end -0.3302 0.4318)
						)
						(arc
							(start 0.3302 0.4318)
							(mid 0.402042 0.402042)
							(end 0.4318 0.3302)
						)
						(arc
							(start 0.4318 -0.3302)
							(mid 0.402042 -0.402042)
							(end 0.3302 -0.4318)
						)
					)
					(width 0)
					(fill yes)
				)
			)
		)
		(pad "2" smd custom
			(at 0 0.762)
			(size 0.2159 0.2159)
			(layers "F.Cu" "F.Mask" "F.Paste")
			(net "DRV_ACT_22")
			(options
				(clearance outline)
				(anchor circle)
			)
			(primitives
				(gr_poly
					(pts
						(arc
							(start -0.3302 -0.4318)
							(mid -0.402042 -0.402042)
							(end -0.4318 -0.3302)
						)
						(arc
							(start -0.4318 0.3302)
							(mid -0.402042 0.402042)
							(end -0.3302 0.4318)
						)
						(arc
							(start 0.3302 0.4318)
							(mid 0.402042 0.402042)
							(end 0.4318 0.3302)
						)
						(arc
							(start 0.4318 -0.3302)
							(mid 0.402042 -0.402042)
							(end 0.3302 -0.4318)
						)
					)
					(width 0)
					(fill yes)
				)
			)
		)
	)
	(footprint ""
		(layer "F.Cu")
		(at 416.284664 -130.21945 -90)
		(property "Reference" "C301"
			(at 0 0 270)
			(layer "F.SilkS")
			(hide yes)
			(effects
				(font
					(size 1.27 1.27)
				)
			)
		)
		(property "Value" "SCD01U16V1KX-GP"
			(at -2.8321 -1.7399 270)
			(unlocked yes)
			(layer "F.Fab")
			(hide yes)
			(effects
				(font
					(size 1.016 1.016)
					(thickness 0.1524)
				)
			)
		)
		(property "Device Type" "C0201H13"
			(at -2.8321 -3.2639 270)
			(unlocked yes)
			(layer "F.Fab")
			(hide yes)
			(effects
				(font
					(size 1.016 1.016)
					(thickness 0.1524)
				)
			)
		)
		(duplicate_pad_numbers_are_jumpers no)
		(fp_rect
			(start -0.2794 0.6477)
			(end 0.2794 -0.6477)
			(stroke
				(width 0)
				(type default)
			)
			(fill no)
			(layer "F.CrtYd")
		)
		(fp_rect
			(start -0.2794 0.6477)
			(end 0.2794 -0.6477)
			(stroke
				(width 0)
				(type default)
			)
			(fill no)
			(layer "F.Fab")
		)
		(pad "1" smd custom
			(at 0 -0.2794 270)
			(size 0.0762 0.0762)
			(layers "F.Cu" "F.Mask" "F.Paste")
			(net "SAS_HDD_RX_N21")
			(options
				(clearance outline)
				(anchor circle)
			)
			(primitives
				(gr_poly
					(pts
						(arc
							(start 0.1524 -0.127)
							(mid 0.137521 -0.162921)
							(end 0.1016 -0.1778)
						)
						(arc
							(start -0.1016 -0.1778)
							(mid -0.137521 -0.162921)
							(end -0.1524 -0.127)
						)
						(arc
							(start -0.1524 0.127)
							(mid -0.137521 0.162921)
							(end -0.1016 0.1778)
						)
						(arc
							(start 0.1016 0.1778)
							(mid 0.137521 0.162921)
							(end 0.1524 0.127)
						)
					)
					(width 0)
					(fill yes)
				)
			)
		)
		(pad "2" smd custom
			(at 0 0.2794 270)
			(size 0.0762 0.0762)
			(layers "F.Cu" "F.Mask" "F.Paste")
			(net "PHY_SCC_B_TO_DRV_B_21_DN")
			(options
				(clearance outline)
				(anchor circle)
			)
			(primitives
				(gr_poly
					(pts
						(arc
							(start 0.1524 -0.127)
							(mid 0.137521 -0.162921)
							(end 0.1016 -0.1778)
						)
						(arc
							(start -0.1016 -0.1778)
							(mid -0.137521 -0.162921)
							(end -0.1524 -0.127)
						)
						(arc
							(start -0.1524 0.127)
							(mid -0.137521 0.162921)
							(end -0.1016 0.1778)
						)
						(arc
							(start 0.1016 0.1778)
							(mid 0.137521 0.162921)
							(end 0.1524 0.127)
						)
					)
					(width 0)
					(fill yes)
				)
			)
		)
	)
	(footprint ""
		(layer "F.Cu")
		(at 189.799976 -203.999846)
		(property "Reference" ""
			(at 0 0 0)
			(layer "F.SilkS")
			(hide yes)
			(effects
				(font
					(size 1.27 1.27)
				)
			)
		)
		(property "Value" "*"
			(at -8.398764 -8.057642 0)
			(unlocked yes)
			(layer "F.Fab")
			(hide yes)
			(effects
				(font
					(size 1.016 1.016)
					(thickness 0.1524)
				)
			)
		)
		(duplicate_pad_numbers_are_jumpers no)
		(fp_poly
			(pts
				(arc
					(start 7.3152 0)
					(mid 0 7.3152)
					(end -7.3152 0)
				)
				(arc
					(start -7.3152 -5.9944)
					(mid 0 -13.3096)
					(end 7.3152 -5.9944)
				)
			)
			(stroke
				(width 0)
				(type default)
			)
			(fill no)
			(layer "B.CrtYd")
		)
		(fp_poly
			(pts
				(arc
					(start 7.3152 0)
					(mid 0 7.3152)
					(end -7.3152 0)
				)
				(arc
					(start -7.3152 -5.9944)
					(mid 0 -13.3096)
					(end 7.3152 -5.9944)
				)
			)
			(stroke
				(width 0)
				(type default)
			)
			(fill no)
			(layer "F.CrtYd")
		)
		(fp_poly
			(pts
				(arc
					(start 7.3152 0)
					(mid 0 7.3152)
					(end -7.3152 0)
				)
				(arc
					(start -7.3152 -5.9944)
					(mid 0 -13.3096)
					(end 7.3152 -5.9944)
				)
			)
			(stroke
				(width 0)
				(type default)
			)
			(fill no)
			(layer "B.Fab")
		)
		(fp_poly
			(pts
				(arc
					(start 7.3152 0)
					(mid 0 7.3152)
					(end -7.3152 0)
				)
				(arc
					(start -7.3152 -5.9944)
					(mid 0 -13.3096)
					(end 7.3152 -5.9944)
				)
			)
			(stroke
				(width 0)
				(type default)
			)
			(fill no)
			(layer "F.Fab")
		)
		(pad "1" thru_hole oval
			(at 0 0)
			(size 14.0208 20.0152)
			(drill 0.0254
				(offset 0 -2.9972)
			)
			(layers "*.Cu" "*.Mask")
			(remove_unused_layers no)
			(net "Net_16")
			(clearance -1.002284)
			(thermal_gap 0.1524)
			(padstack
				(mode front_inner_back)
				(layer "Inner"
					(shape custom)
					(size 2.928012 2.928012)
					(options
						(anchor circle)
					)
					(primitives
						(gr_poly
							(pts
								(arc
									(start 4.571746 -2.084324)
									(mid 0.000333 7.430372)
									(end -4.571492 -2.084324)
								)
								(arc
									(start -4.571492 -2.084324)
									(mid -3.570296 -3.611977)
									(end -2.875026 -5.30098)
								)
								(arc
									(start -2.875026 -5.30098)
									(mid 0.000217 -7.43089)
									(end 2.87528 -5.30098)
								)
								(arc
									(start 2.87528 -5.30098)
									(mid 3.570511 -3.611956)
									(end 4.571746 -2.084324)
								)
							)
							(width 0)
							(fill yes)
						)
					)
					(clearance 0.1524)
				)
				(layer "B.Cu"
					(shape oval)
					(size 14.0208 20.0152)
					(offset 0 -2.9972)
					(clearance -1.002284)
				)
			)
		)
		(zone
			(layers "F.Cu" "B.Cu" "In1.Cu" "In2.Cu" "In3.Cu" "In4.Cu" "In5.Cu" "In6.Cu")
			(hatch none 0.5)
			(connect_pads
				(clearance 0)
			)
			(min_thickness 0.25)
			(keepout
				(tracks not_allowed)
				(vias allowed)
				(pads allowed)
				(copperpour not_allowed)
				(footprints allowed)
			)
			(placement
				(enabled no)
				(sheetname "")
			)
			(fill
				(thermal_gap 0.5)
				(thermal_bridge_width 0.5)
				(island_removal_mode 0)
			)
			(polygon
				(pts
					(arc
						(start 182.789576 -209.994246)
						(mid 189.799976 -217.004646)
						(end 196.810376 -209.994246)
					)
					(arc
						(start 196.810376 -203.999846)
						(mid 189.799976 -196.989446)
						(end 182.789576 -203.999846)
					)
				)
			)
		)
	)
	(footprint ""
		(layer "F.Cu")
		(at 424.434 -152.908 180)
		(property "Reference" "C303"
			(at 0 0 180)
			(layer "F.SilkS")
			(hide yes)
			(effects
				(font
					(size 1.27 1.27)
				)
			)
		)
		(property "Value" "SC1U16V3KX-5GP"
			(at 0 -2.8194 180)
			(unlocked yes)
			(layer "F.Fab")
			(hide yes)
			(effects
				(font
					(size 1.016 1.016)
					(thickness 0.1524)
				)
			)
		)
		(property "Device Type" "C603H36"
			(at 0 -4.3434 180)
			(unlocked yes)
			(layer "F.Fab")
			(hide yes)
			(effects
				(font
					(size 1.016 1.016)
					(thickness 0.1524)
				)
			)
		)
		(duplicate_pad_numbers_are_jumpers no)
		(fp_line
			(start 0.508 0)
			(end -0.508 0)
			(stroke
				(width 0.2032)
				(type default)
			)
			(layer "F.SilkS")
		)
		(fp_rect
			(start -0.5842 1.3335)
			(end 0.5842 -1.3335)
			(stroke
				(width 0)
				(type default)
			)
			(fill no)
			(layer "F.CrtYd")
		)
		(fp_rect
			(start -0.5842 1.3335)
			(end 0.5842 -1.3335)
			(stroke
				(width 0)
				(type default)
			)
			(fill no)
			(layer "F.Fab")
		)
		(pad "1" smd custom
			(at 0 -0.762 180)
			(size 0.2159 0.2159)
			(layers "F.Cu" "F.Mask" "F.Paste")
			(net "P5V_HDD21")
			(options
				(clearance outline)
				(anchor circle)
			)
			(primitives
				(gr_poly
					(pts
						(arc
							(start -0.3302 -0.4318)
							(mid -0.402042 -0.402042)
							(end -0.4318 -0.3302)
						)
						(arc
							(start -0.4318 0.3302)
							(mid -0.402042 0.402042)
							(end -0.3302 0.4318)
						)
						(arc
							(start 0.3302 0.4318)
							(mid 0.402042 0.402042)
							(end 0.4318 0.3302)
						)
						(arc
							(start 0.4318 -0.3302)
							(mid 0.402042 -0.402042)
							(end 0.3302 -0.4318)
						)
					)
					(width 0)
					(fill yes)
				)
			)
		)
		(pad "2" smd custom
			(at 0 0.762 180)
			(size 0.2159 0.2159)
			(layers "F.Cu" "F.Mask" "F.Paste")
			(net "GND")
			(options
				(clearance outline)
				(anchor circle)
			)
			(primitives
				(gr_poly
					(pts
						(arc
							(start -0.3302 -0.4318)
							(mid -0.402042 -0.402042)
							(end -0.4318 -0.3302)
						)
						(arc
							(start -0.4318 0.3302)
							(mid -0.402042 0.402042)
							(end -0.3302 0.4318)
						)
						(arc
							(start 0.3302 0.4318)
							(mid 0.402042 0.402042)
							(end 0.4318 0.3302)
						)
						(arc
							(start 0.4318 -0.3302)
							(mid 0.402042 -0.402042)
							(end 0.3302 -0.4318)
						)
					)
					(width 0)
					(fill yes)
				)
			)
		)
	)
)
